# S9S_MB_2U (Grand Teton) — schematic netlist excerpt (pin names and nets, part order shuffled) for the footprints in the layout excerpt that follows; sources: Cadence DE-HDL packaged netlist, KiCad conversion of 03242023_DA0F0TMBIJ0_F0T_Motherboard_J_brd_V01_OCP.brd

PC373  Q_CAP  2.2UF 10V 10% X6S  pkg C0402  page 297 : A = PVCCD_HV_CPU1_VDD1 ; B = GND
R3052  Q_RES  33.2 1% CHIP  pkg 0402LF  page 228 : A = SMB_HOST_3V3AUX_SCL_R5 ; B = SMB_HOST_ME_SCL

(kicad_pcb
	(version 20260206)
	(generator "pcbnew")
	(generator_version "10.0")
	(general
		(thickness 1.6)
		(legacy_teardrops no)
	)
	(paper "A4")
	(title_block
		(title "03242023_DA0F0TMBIJ0_F0T_Motherboard_J_brd_V01_OCP.brd")
		(comment 1 "Grand Teton / footprints 1668-1669 of 6105")
	)
	(layers
		(0 "F.Cu" signal "TOP")
		(4 "In1.Cu" signal "GND")
		(6 "In2.Cu" signal "IN1")
		(8 "In3.Cu" signal "GND1")
		(10 "In4.Cu" signal "IN2")
		(12 "In5.Cu" signal "GND2")
		(14 "In6.Cu" signal "IN3")
		(16 "In7.Cu" signal "GND3")
		(18 "In8.Cu" signal "VCC")
		(20 "In9.Cu" signal "VCC1")
		(22 "In10.Cu" signal "GND4")
		(24 "In11.Cu" signal "IN4")
		(26 "In12.Cu" signal "GND5")
		(28 "In13.Cu" signal "IN5")
		(30 "In14.Cu" signal "GND6")
		(32 "In15.Cu" signal "IN6")
		(34 "In16.Cu" signal "GND7")
		(2 "B.Cu" signal "BOTTOM")
		(9 "F.Adhes" user "F.Adhesive")
		(11 "B.Adhes" user "B.Adhesive")
		(13 "F.Paste" user "Package Geometry/Pastemask Top")
		(15 "B.Paste" user "Package Geometry/Pastemask Bottom")
		(5 "F.SilkS" user "Ref Des/Silkscreen Top")
		(7 "B.SilkS" user "Ref Des/Silkscreen Bottom")
		(1 "F.Mask" user "Board Geometry/Soldermask Top")
		(3 "B.Mask" user "Board Geometry/Soldermask Bottom")
		(17 "Dwgs.User" user "User.Drawings")
		(19 "Cmts.User" user "User.Comments")
		(21 "Eco1.User" user "User.Eco1")
		(23 "Eco2.User" user "User.Eco2")
		(25 "Edge.Cuts" user "Board Geometry/Outline")
		(27 "Margin" user)
		(31 "F.CrtYd" user "Package Geometry/Place Bound Top")
		(29 "B.CrtYd" user "Package Geometry/Place Bound Bottom")
		(35 "F.Fab" user "Ref Des/Assembly Top")
		(33 "B.Fab" user "Ref Des/Assembly Bottom")
	)
	(footprint ""
		(layer "F.Cu")
		(at 52.423314 -161.539174 180)
		(property "Reference" "PC373"
			(at 0 0 180)
			(layer "F.SilkS")
			(hide yes)
			(effects
				(font
					(size 1.27 1.27)
				)
			)
		)
		(property "Value" ""
			(at 0 0 180)
			(layer "F.Fab")
			(effects
				(font
					(size 1.27 1.27)
				)
			)
		)
		(duplicate_pad_numbers_are_jumpers no)
		(fp_line
			(start 0.7874 0.4064)
			(end -0.7874 0.4064)
			(stroke
				(width 0.1524)
				(type default)
			)
			(layer "F.SilkS")
		)
		(fp_line
			(start 0.7874 -0.4064)
			(end 0.7874 0.4064)
			(stroke
				(width 0.1524)
				(type default)
			)
			(layer "F.SilkS")
		)
		(fp_line
			(start -0.7874 0.4064)
			(end -0.7874 -0.4064)
			(stroke
				(width 0.1524)
				(type default)
			)
			(layer "F.SilkS")
		)
		(fp_line
			(start -0.7874 -0.4064)
			(end 0.7874 -0.4064)
			(stroke
				(width 0.1524)
				(type default)
			)
			(layer "F.SilkS")
		)
		(fp_line
			(start 0.67945 0.3048)
			(end 0.120396 0.3048)
			(stroke
				(width 0.1)
				(type default)
			)
			(layer "F.Fab")
		)
		(fp_line
			(start 0.67945 -0.3048)
			(end 0.67945 0.3048)
			(stroke
				(width 0.1)
				(type default)
			)
			(layer "F.Fab")
		)
		(fp_line
			(start 0.12065 -0.2794)
			(end 0.12065 -0.3048)
			(stroke
				(width 0.1)
				(type default)
			)
			(layer "F.Fab")
		)
		(fp_line
			(start 0.12065 -0.3048)
			(end 0.67945 -0.3048)
			(stroke
				(width 0.1)
				(type default)
			)
			(layer "F.Fab")
		)
		(fp_line
			(start 0.120396 0.3048)
			(end 0.120396 0.2794)
			(stroke
				(width 0.1)
				(type default)
			)
			(layer "F.Fab")
		)
		(fp_line
			(start 0.120396 0.2794)
			(end -0.12065 0.2794)
			(stroke
				(width 0.1)
				(type default)
			)
			(layer "F.Fab")
		)
		(fp_line
			(start -0.12065 0.3048)
			(end -0.67945 0.3048)
			(stroke
				(width 0.1)
				(type default)
			)
			(layer "F.Fab")
		)
		(fp_line
			(start -0.12065 0.2794)
			(end -0.12065 0.3048)
			(stroke
				(width 0.1)
				(type default)
			)
			(layer "F.Fab")
		)
		(fp_line
			(start -0.12065 -0.2794)
			(end 0.12065 -0.2794)
			(stroke
				(width 0.1)
				(type default)
			)
			(layer "F.Fab")
		)
		(fp_line
			(start -0.12065 -0.305054)
			(end -0.12065 -0.2794)
			(stroke
				(width 0.1)
				(type default)
			)
			(layer "F.Fab")
		)
		(fp_line
			(start -0.67945 0.3048)
			(end -0.67945 -0.305054)
			(stroke
				(width 0.1)
				(type default)
			)
			(layer "F.Fab")
		)
		(fp_line
			(start -0.67945 -0.305054)
			(end -0.12065 -0.305054)
			(stroke
				(width 0.1)
				(type default)
			)
			(layer "F.Fab")
		)
		(pad "1" smd circle
			(at -0.40005 0 180)
			(size 0 0)
			(layers "F.Cu" "F.Mask" "F.Paste")
			(net "PVCCD_HV_CPU1_VDD1")
		)
		(pad "2" smd circle
			(at 0.40005 0 180)
			(size 0 0)
			(layers "F.Cu" "F.Mask" "F.Paste")
			(net "GND")
		)
	)
	(footprint ""
		(layer "F.Cu")
		(at 9.652 -51.018948)
		(property "Reference" "R3052"
			(at 0 0 0)
			(layer "F.SilkS")
			(hide yes)
			(effects
				(font
					(size 1.27 1.27)
				)
			)
		)
		(property "Value" ""
			(at 0 0 0)
			(layer "F.Fab")
			(effects
				(font
					(size 1.27 1.27)
				)
			)
		)
		(duplicate_pad_numbers_are_jumpers no)
		(fp_line
			(start -0.7874 -0.4064)
			(end 0.7874 -0.4064)
			(stroke
				(width 0.1524)
				(type default)
			)
			(layer "F.SilkS")
		)
		(fp_line
			(start -0.7874 0.4064)
			(end -0.7874 -0.4064)
			(stroke
				(width 0.1524)
				(type default)
			)
			(layer "F.SilkS")
		)
		(fp_line
			(start 0.7874 -0.4064)
			(end 0.7874 0.4064)
			(stroke
				(width 0.1524)
				(type default)
			)
			(layer "F.SilkS")
		)
		(fp_line
			(start 0.7874 0.4064)
			(end -0.7874 0.4064)
			(stroke
				(width 0.1524)
				(type default)
			)
			(layer "F.SilkS")
		)
		(fp_line
			(start -0.67945 -0.305054)
			(end -0.12065 -0.305054)
			(stroke
				(width 0.1)
				(type default)
			)
			(layer "F.Fab")
		)
		(fp_line
			(start -0.67945 0.3048)
			(end -0.67945 -0.305054)
			(stroke
				(width 0.1)
				(type default)
			)
			(layer "F.Fab")
		)
		(fp_line
			(start -0.12065 -0.305054)
			(end -0.12065 -0.2794)
			(stroke
				(width 0.1)
				(type default)
			)
			(layer "F.Fab")
		)
		(fp_line
			(start -0.12065 -0.2794)
			(end 0.12065 -0.2794)
			(stroke
				(width 0.1)
				(type default)
			)
			(layer "F.Fab")
		)
		(fp_line
			(start -0.12065 0.2794)
			(end -0.12065 0.3048)
			(stroke
				(width 0.1)
				(type default)
			)
			(layer "F.Fab")
		)
		(fp_line
			(start -0.12065 0.3048)
			(end -0.67945 0.3048)
			(stroke
				(width 0.1)
				(type default)
			)
			(layer "F.Fab")
		)
		(fp_line
			(start 0.120396 0.2794)
			(end -0.12065 0.2794)
			(stroke
				(width 0.1)
				(type default)
			)
			(layer "F.Fab")
		)
		(fp_line
			(start 0.120396 0.3048)
			(end 0.120396 0.2794)
			(stroke
				(width 0.1)
				(type default)
			)
			(layer "F.Fab")
		)
		(fp_line
			(start 0.12065 -0.3048)
			(end 0.67945 -0.3048)
			(stroke
				(width 0.1)
				(type default)
			)
			(layer "F.Fab")
		)
		(fp_line
			(start 0.12065 -0.2794)
			(end 0.12065 -0.3048)
			(stroke
				(width 0.1)
				(type default)
			)
			(layer "F.Fab")
		)
		(fp_line
			(start 0.67945 -0.3048)
			(end 0.67945 0.3048)
			(stroke
				(width 0.1)
				(type default)
			)
			(layer "F.Fab")
		)
		(fp_line
			(start 0.67945 0.3048)
			(end 0.120396 0.3048)
			(stroke
				(width 0.1)
				(type default)
			)
			(layer "F.Fab")
		)
		(pad "1" smd circle
			(at -0.40005 0)
			(size 0 0)
			(layers "F.Cu" "F.Mask" "F.Paste")
			(net "SMB_HOST_3V3AUX_SCL_R5")
		)
		(pad "2" smd circle
			(at 0.40005 0)
			(size 0 0)
			(layers "F.Cu" "F.Mask" "F.Paste")
			(net "SMB_HOST_ME_SCL")
		)
	)
)
